# BASEBOARD_FAB2 (Tioga Pass) — schematic netlist excerpt (pin names and nets, part order shuffled) for the footprints in the layout excerpt that follows; sources: Cadence DE-HDL packaged netlist, KiCad conversion of Wiwynn_Tioga_Pass_MB.brd

J4B2  SCONN120_H61426002  CONN  pkg SM  page 193
  IOA1  = P12V_STBY
  IOA2  = P12V_STBY
  IOA3  = P12V_STBY
  IOA4  = P12V_STBY
  IOA5  = P12V_STBY
  IOA6  = P12V_STBY
  IOA7  = P12V_STBY
  IOA8  = P12V_STBY
  IOA9  = GND
  IOA10  = GND
  IOA11  = P3V3_STBY
  IOA12  = GND
  IOA13  = P5V_STBY
  IOA14  = GND
  IOA15  = FM_P1V8MCP_CPU1_EN
  IOA16  = FM_PVCCIOMCP_CPU1_EN
  IOA17  = GND
  IOA18  = SMB_VR_STBY_LVC3_SCL
  IOA19  = SVID_ALERT0_CPU1_R_N
  IOA20  = SVID_CLK0_CPU1_R
  IOB1  = P12V_STBY
  IOB2  = P12V_STBY
  IOB3  = P12V_STBY
  IOB4  = P12V_STBY
  IOB5  = P12V_STBY
  IOB6  = P12V_STBY
  IOB7  = P12V_STBY
  IOB8  = P12V_STBY
  IOB9  = GND
  IOB10  = GND
  IOB11  = P3V3_STBY
  IOB12  = GND
  IOB13  = P5V_STBY
  IOB14  = GND
  IOB15  = PWRGD_P1V8MCP_CPU1
  IOB16  = PWRGD_PVCCIOMCP_CPU1
  IOB17  = GND
  IOB18  = SMB_VR_STBY_LVC3_SDA
  IOB19  = SVID_ALERT1_CPU1_R_N
  IOB20  = SVID_DIO0_CPU1_R
  IOC1  = GND
  IOC2  = GND
  IOC3  = GND
  IOC4  = GND
  IOC5  = GND
  IOC6  = GND
  IOC7  = GND
  IOC8  = GND
  IOC9  = GND
  IOC10  = GND
  IOC11  = P3V3_STBY
  IOC12  = GND
  IOC13  = P5V_STBY
  IOC14  = GND
  IOC15  = GND
  IOC16  = GND
  IOC17  = PVCCIOMCP_CPU1
  IOC18  = PVCCIOMCP_CPU1
  IOC19  = PVCCIOMCP_CPU1
  IOC20  = FM_PVCCMCP_CPU1_EN
  IOD1  = P3V3
  IOD2  = GND
  IOD3  = GND
  IOD4  = GND
  IOD5  = GND
  IOD6  = GND
  IOD7  = GND
  IOD8  = GND
  IOD9  = GND
  IOD10  = GND
  IOD11  = GND
  IOD12  = GND
  IOD13  = GND
  IOD14  = GND
  IOD15  = GND
  IOD16  = GND
  IOD17  = PVCCIOMCP_CPU1
  IOD18  = PVCCIOMCP_CPU1
  IOD19  = PVCCIOMCP_CPU1
  IOD20  = PWRGD_PVCCMCP_CPU1
  IOE1  = FM_CPU1_VRM_322M_156M_OSC_EN
  IOE2  = GND
  IOE3  = GND
  IOE4  = GND
  IOE5  = GND
  IOE6  = GND
  IOE7  = GND
  IOE8  = VSENSE_PVCCIOMCP_CPU1_SKT_VSEN
  IOE9  = GND
  IOE10  = VR_PVCCIOMCP_CPU1_XADDR1
  IOE11  = GND
  IOE12  = GND
  IOE13  = GND
  IOE14  = GND
  IOE15  = PVCCIOMCP_CPU1
  IOE16  = PVCCIOMCP_CPU1
  IOE17  = PVCCIOMCP_CPU1
  IOE18  = PVCCIOMCP_CPU1
  IOE19  = PVCCIOMCP_CPU1
  IOE20  = SVID_CLK1_CPU1_R
  IOF1  = PVCCIO_CPU1
  IOF2  = GND
  IOF3  = GND
  IOF4  = GND
  IOF5  = GND
  IOF6  = GND
  IOF7  = GND
  IOF8  = VSENSE_PVCCIOMCP_CPU1_SKT_VRTN
  IOF9  = GND
  IOF10  = VR_PVCCMCP_CPU1_XADDR2
  IOF11  = GND
  IOF12  = GND
  IOF13  = GND
  IOF14  = GND
  IOF15  = PVCCIOMCP_CPU1
  IOF16  = PVCCIOMCP_CPU1
  IOF17  = PVCCIOMCP_CPU1
  IOF18  = PVCCIOMCP_CPU1
  IOF19  = PVCCIOMCP_CPU1
  IOF20  = SVID_DIO1_CPU1_R

(kicad_pcb
	(version 20260206)
	(generator "pcbnew")
	(generator_version "10.0")
	(general
		(thickness 1.6)
		(legacy_teardrops no)
	)
	(paper "A4")
	(title_block
		(title "Wiwynn_Tioga_Pass_MB.brd")
		(comment 1 "Tioga Pass / footprint 858 of 4770 (J4B2), pads 1-51 of 122")
	)
	(layers
		(0 "F.Cu" signal "TOP")
		(4 "In1.Cu" signal "L2GND")
		(6 "In2.Cu" signal "L3")
		(8 "In3.Cu" signal "L4GND")
		(10 "In4.Cu" signal "L5")
		(12 "In5.Cu" signal "L6GND")
		(14 "In6.Cu" signal "L7VCC")
		(16 "In7.Cu" signal "L8VCC")
		(18 "In8.Cu" signal "L9GND")
		(20 "In9.Cu" signal "L10")
		(22 "In10.Cu" signal "L11GND")
		(24 "In11.Cu" signal "L12")
		(26 "In12.Cu" signal "L13GND")
		(2 "B.Cu" signal "BOTTOM")
		(9 "F.Adhes" user "F.Adhesive")
		(11 "B.Adhes" user "B.Adhesive")
		(13 "F.Paste" user "Package Geometry/Pastemask Top")
		(15 "B.Paste" user "Package Geometry/Pastemask Bottom")
		(5 "F.SilkS" user "Ref Des/Silkscreen Top")
		(7 "B.SilkS" user "Ref Des/Silkscreen Bottom")
		(1 "F.Mask" user "Board Geometry/Soldermask Top")
		(3 "B.Mask" user "Board Geometry/Soldermask Bottom")
		(17 "Dwgs.User" user "User.Drawings")
		(19 "Cmts.User" user "User.Comments")
		(21 "Eco1.User" user "User.Eco1")
		(23 "Eco2.User" user "User.Eco2")
		(25 "Edge.Cuts" user "Board Geometry/Outline")
		(27 "Margin" user)
		(31 "F.CrtYd" user "Package Geometry/Place Bound Top")
		(29 "B.CrtYd" user "Package Geometry/Place Bound Bottom")
		(35 "F.Fab" user "Ref Des/Assembly Top")
		(33 "B.Fab" user "Ref Des/Assembly Bottom")
	)
	(footprint ""
		(layer "F.Cu")
		(at 164.615114 -115.55095 90)
		(property "Reference" "J4B2"
			(at -3.59283 -5.018024 90)
			(unlocked yes)
			(layer "F.SilkS")
			(effects
				(font
					(size 0.7874 0.5842)
					(thickness 0.1524)
				)
			)
		)
		(property "Value" ""
			(at 0 0 90)
			(layer "F.Fab")
			(effects
				(font
					(size 1.27 1.27)
				)
			)
		)
		(duplicate_pad_numbers_are_jumpers no)
		(pad "" np_thru_hole circle
			(at -3.175 26.5557 90)
			(size 0.254 0.254)
			(drill 1.27)
			(layers "*.Cu" "*.Mask")
			(clearance 0.8255)
			(thermal_gap 0.8255)
		)
		(pad "" np_thru_hole circle
			(at -0.127 -2.4257 90)
			(size 0.254 0.254)
			(drill 1.27)
			(layers "*.Cu" "*.Mask")
			(clearance 0.8255)
			(thermal_gap 0.8255)
		)
		(pad "A1" smd circle
			(at 0 0 90)
			(size 0.635 0.635)
			(layers "F.Cu" "F.Mask" "F.Paste")
			(net "P12V_STBY")
		)
		(pad "A2" smd circle
			(at 0 1.27 90)
			(size 0.635 0.635)
			(layers "F.Cu" "F.Mask" "F.Paste")
			(net "P12V_STBY")
		)
		(pad "A3" smd circle
			(at 0 2.54 90)
			(size 0.635 0.635)
			(layers "F.Cu" "F.Mask" "F.Paste")
			(net "P12V_STBY")
		)
		(pad "A4" smd circle
			(at 0 3.81 90)
			(size 0.635 0.635)
			(layers "F.Cu" "F.Mask" "F.Paste")
			(net "P12V_STBY")
		)
		(pad "A5" smd circle
			(at 0 5.08 90)
			(size 0.635 0.635)
			(layers "F.Cu" "F.Mask" "F.Paste")
			(net "P12V_STBY")
		)
		(pad "A6" smd circle
			(at 0 6.35 90)
			(size 0.635 0.635)
			(layers "F.Cu" "F.Mask" "F.Paste")
			(net "P12V_STBY")
		)
		(pad "A7" smd circle
			(at 0 7.62 90)
			(size 0.635 0.635)
			(layers "F.Cu" "F.Mask" "F.Paste")
			(net "P12V_STBY")
		)
		(pad "A8" smd circle
			(at 0 8.89 90)
			(size 0.635 0.635)
			(layers "F.Cu" "F.Mask" "F.Paste")
			(net "P12V_STBY")
		)
		(pad "A9" smd circle
			(at 0 10.16 90)
			(size 0.635 0.635)
			(layers "F.Cu" "F.Mask" "F.Paste")
			(net "GND")
		)
		(pad "A10" smd circle
			(at 0 11.43 90)
			(size 0.635 0.635)
			(layers "F.Cu" "F.Mask" "F.Paste")
			(net "GND")
		)
		(pad "A11" smd circle
			(at 0 12.7 90)
			(size 0.635 0.635)
			(layers "F.Cu" "F.Mask" "F.Paste")
			(net "P3V3_STBY")
		)
		(pad "A12" smd circle
			(at 0 13.97 90)
			(size 0.635 0.635)
			(layers "F.Cu" "F.Mask" "F.Paste")
			(net "GND")
		)
		(pad "A13" smd circle
			(at 0 15.24 90)
			(size 0.635 0.635)
			(layers "F.Cu" "F.Mask" "F.Paste")
			(net "P5V_STBY")
		)
		(pad "A14" smd circle
			(at 0 16.51 90)
			(size 0.635 0.635)
			(layers "F.Cu" "F.Mask" "F.Paste")
			(net "GND")
		)
		(pad "A15" smd circle
			(at 0 17.78 90)
			(size 0.635 0.635)
			(layers "F.Cu" "F.Mask" "F.Paste")
			(net "FM_P1V8MCP_CPU1_EN")
		)
		(pad "A16" smd circle
			(at 0 19.05 90)
			(size 0.635 0.635)
			(layers "F.Cu" "F.Mask" "F.Paste")
			(net "FM_PVCCIOMCP_CPU1_EN")
		)
		(pad "A17" smd circle
			(at 0 20.32 90)
			(size 0.635 0.635)
			(layers "F.Cu" "F.Mask" "F.Paste")
			(net "GND")
		)
		(pad "A18" smd circle
			(at 0 21.59 90)
			(size 0.635 0.635)
			(layers "F.Cu" "F.Mask" "F.Paste")
			(net "SMB_VR_STBY_LVC3_SCL")
		)
		(pad "A19" smd circle
			(at 0 22.86 90)
			(size 0.635 0.635)
			(layers "F.Cu" "F.Mask" "F.Paste")
			(net "SVID_ALERT0_CPU1_R_N")
		)
		(pad "A20" smd circle
			(at 0 24.13 90)
			(size 0.635 0.635)
			(layers "F.Cu" "F.Mask" "F.Paste")
			(net "SVID_CLK0_CPU1_R")
		)
		(pad "B1" smd circle
			(at -1.27 0 90)
			(size 0.635 0.635)
			(layers "F.Cu" "F.Mask" "F.Paste")
			(net "P12V_STBY")
		)
		(pad "B2" smd circle
			(at -1.27 1.27 90)
			(size 0.635 0.635)
			(layers "F.Cu" "F.Mask" "F.Paste")
			(net "P12V_STBY")
		)
		(pad "B3" smd circle
			(at -1.27 2.54 90)
			(size 0.635 0.635)
			(layers "F.Cu" "F.Mask" "F.Paste")
			(net "P12V_STBY")
		)
		(pad "B4" smd circle
			(at -1.27 3.81 90)
			(size 0.635 0.635)
			(layers "F.Cu" "F.Mask" "F.Paste")
			(net "P12V_STBY")
		)
		(pad "B5" smd circle
			(at -1.27 5.08 90)
			(size 0.635 0.635)
			(layers "F.Cu" "F.Mask" "F.Paste")
			(net "P12V_STBY")
		)
		(pad "B6" smd circle
			(at -1.27 6.35 90)
			(size 0.635 0.635)
			(layers "F.Cu" "F.Mask" "F.Paste")
			(net "P12V_STBY")
		)
		(pad "B7" smd circle
			(at -1.27 7.62 90)
			(size 0.635 0.635)
			(layers "F.Cu" "F.Mask" "F.Paste")
			(net "P12V_STBY")
		)
		(pad "B8" smd circle
			(at -1.27 8.89 90)
			(size 0.635 0.635)
			(layers "F.Cu" "F.Mask" "F.Paste")
			(net "P12V_STBY")
		)
		(pad "B9" smd circle
			(at -1.27 10.16 90)
			(size 0.635 0.635)
			(layers "F.Cu" "F.Mask" "F.Paste")
			(net "GND")
		)
		(pad "B10" smd circle
			(at -1.27 11.43 90)
			(size 0.635 0.635)
			(layers "F.Cu" "F.Mask" "F.Paste")
			(net "GND")
		)
		(pad "B11" smd circle
			(at -1.27 12.7 90)
			(size 0.635 0.635)
			(layers "F.Cu" "F.Mask" "F.Paste")
			(net "P3V3_STBY")
		)
		(pad "B12" smd circle
			(at -1.27 13.97 90)
			(size 0.635 0.635)
			(layers "F.Cu" "F.Mask" "F.Paste")
			(net "GND")
		)
		(pad "B13" smd circle
			(at -1.27 15.24 90)
			(size 0.635 0.635)
			(layers "F.Cu" "F.Mask" "F.Paste")
			(net "P5V_STBY")
		)
		(pad "B14" smd circle
			(at -1.27 16.51 90)
			(size 0.635 0.635)
			(layers "F.Cu" "F.Mask" "F.Paste")
			(net "GND")
		)
		(pad "B15" smd circle
			(at -1.27 17.78 90)
			(size 0.635 0.635)
			(layers "F.Cu" "F.Mask" "F.Paste")
			(net "PWRGD_P1V8MCP_CPU1")
		)
		(pad "B16" smd circle
			(at -1.27 19.05 90)
			(size 0.635 0.635)
			(layers "F.Cu" "F.Mask" "F.Paste")
			(net "PWRGD_PVCCIOMCP_CPU1")
		)
		(pad "B17" smd circle
			(at -1.27 20.32 90)
			(size 0.635 0.635)
			(layers "F.Cu" "F.Mask" "F.Paste")
			(net "GND")
		)
		(pad "B18" smd circle
			(at -1.27 21.59 90)
			(size 0.635 0.635)
			(layers "F.Cu" "F.Mask" "F.Paste")
			(net "SMB_VR_STBY_LVC3_SDA")
		)
		(pad "B19" smd circle
			(at -1.27 22.86 90)
			(size 0.635 0.635)
			(layers "F.Cu" "F.Mask" "F.Paste")
			(net "SVID_ALERT1_CPU1_R_N")
		)
		(pad "B20" smd circle
			(at -1.27 24.13 90)
			(size 0.635 0.635)
			(layers "F.Cu" "F.Mask" "F.Paste")
			(net "SVID_DIO0_CPU1_R")
		)
		(pad "C1" smd circle
			(at -2.54 0 90)
			(size 0.635 0.635)
			(layers "F.Cu" "F.Mask" "F.Paste")
			(net "GND")
		)
		(pad "C2" smd circle
			(at -2.54 1.27 90)
			(size 0.635 0.635)
			(layers "F.Cu" "F.Mask" "F.Paste")
			(net "GND")
		)
		(pad "C3" smd circle
			(at -2.54 2.54 90)
			(size 0.635 0.635)
			(layers "F.Cu" "F.Mask" "F.Paste")
			(net "GND")
		)
		(pad "C4" smd circle
			(at -2.54 3.81 90)
			(size 0.635 0.635)
			(layers "F.Cu" "F.Mask" "F.Paste")
			(net "GND")
		)
		(pad "C5" smd circle
			(at -2.54 5.08 90)
			(size 0.635 0.635)
			(layers "F.Cu" "F.Mask" "F.Paste")
			(net "GND")
		)
		(pad "C6" smd circle
			(at -2.54 6.35 90)
			(size 0.635 0.635)
			(layers "F.Cu" "F.Mask" "F.Paste")
			(net "GND")
		)
		(pad "C7" smd circle
			(at -2.54 7.62 90)
			(size 0.635 0.635)
			(layers "F.Cu" "F.Mask" "F.Paste")
			(net "GND")
		)
		(pad "C8" smd circle
			(at -2.54 8.89 90)
			(size 0.635 0.635)
			(layers "F.Cu" "F.Mask" "F.Paste")
			(net "GND")
		)
		(pad "C9" smd circle
			(at -2.54 10.16 90)
			(size 0.635 0.635)
			(layers "F.Cu" "F.Mask" "F.Paste")
			(net "GND")
		)
	)
)
